# TIMECARD (Time Appliance Project (Time Card)) — schematic netlist excerpt (pin names and nets, part order shuffled) for the footprints in the layout excerpt that follows; sources: Cadence DE-HDL packaged netlist, KiCad conversion of R4006-B0001-02_R01.brd

TP55  TP_PIONT  pkg TP010CT020B030_PTH  page 25 : \1\ = XP1R2V_FPGA
SP21  SOLDER_PREFORM  pkg 0201_SOLDER_PREFORM_4MIL  page 34 : \1\ = NC ; \2\ = NC
R425  RESISTOR  100OHM 1%  pkg SMC_0402R_H016  page 26 : \1\ = FPGA_OUT_GPS_LED_BLUE_N ; \2\ = UNNAMED_14_LED4PV14_I269_1

(kicad_pcb
	(version 20260206)
	(generator "pcbnew")
	(generator_version "10.0")
	(general
		(thickness 1.6)
		(legacy_teardrops no)
	)
	(paper "A4")
	(title_block
		(title "timecard-production-celestica-r4006 — R4006-B0001-02_R01.brd")
		(comment 1 "Time Appliance Project (Time Card) / footprints 623-625 of 1113")
	)
	(layers
		(0 "F.Cu" signal "TOP")
		(4 "In1.Cu" signal "L02_GND1")
		(6 "In2.Cu" signal "L03_SIG1")
		(8 "In3.Cu" signal "L04_GND2")
		(10 "In4.Cu" signal "L05_VCC1")
		(12 "In5.Cu" signal "L06_VCC2")
		(14 "In6.Cu" signal "L07_GND3")
		(16 "In7.Cu" signal "L08_SIG2")
		(18 "In8.Cu" signal "L09_GND4")
		(2 "B.Cu" signal "BOTTOM")
		(9 "F.Adhes" user "F.Adhesive")
		(11 "B.Adhes" user "B.Adhesive")
		(13 "F.Paste" user "Package Geometry/Pastemask Top")
		(15 "B.Paste" user "Package Geometry/Pastemask Bottom")
		(5 "F.SilkS" user "Ref Des/Silkscreen Top")
		(7 "B.SilkS" user "Ref Des/Silkscreen Bottom")
		(1 "F.Mask" user "Board Geometry/Soldermask Top")
		(3 "B.Mask" user "Board Geometry/Soldermask Bottom")
		(17 "Dwgs.User" user "User.Drawings")
		(19 "Cmts.User" user "User.Comments")
		(21 "Eco1.User" user "User.Eco1")
		(23 "Eco2.User" user "User.Eco2")
		(25 "Edge.Cuts" user "Board Geometry/Outline")
		(27 "Margin" user)
		(31 "F.CrtYd" user "Package Geometry/Place Bound Top")
		(29 "B.CrtYd" user "Package Geometry/Place Bound Bottom")
		(35 "F.Fab" user "Ref Des/Assembly Top")
		(33 "B.Fab" user "Ref Des/Assembly Bottom")
	)
	(footprint ""
		(layer "F.Cu")
		(at 5.842 -81.534 90)
		(property "Reference" "R425"
			(at -2.667 -0.34163 90)
			(unlocked yes)
			(layer "F.SilkS")
			(effects
				(font
					(size 0.7874 0.5842)
					(thickness 0.1524)
				)
			)
		)
		(property "Value" "VAL*"
			(at 0.02032 2.13233 90)
			(unlocked yes)
			(layer "F.Fab")
			(hide yes)
			(effects
				(font
					(size 0.7874 0.5842)
					(thickness 0.1524)
				)
			)
		)
		(property "Device Type" "RESISTOR-G155-11000-01,100OHM,A"
			(at 0.008382 1.210564 90)
			(unlocked yes)
			(layer "F.Fab")
			(hide yes)
			(effects
				(font
					(size 0.7874 0.5842)
					(thickness 0.1524)
				)
			)
		)
		(property "User Part Number" "PARTNUM*"
			(at 0.02032 4.024884 90)
			(unlocked yes)
			(layer "Cmts.User")
			(hide yes)
			(effects
				(font
					(size 0.7874 0.5842)
					(thickness 0.1524)
				)
			)
		)
		(property "Tolerance" "TOL*"
			(at 0.044704 3.05435 90)
			(unlocked yes)
			(layer "Cmts.User")
			(hide yes)
			(effects
				(font
					(size 0.7874 0.5842)
					(thickness 0.1524)
				)
			)
		)
		(duplicate_pad_numbers_are_jumpers no)
		(fp_line
			(start 1.143 -0.5588)
			(end -1.143 -0.5588)
			(stroke
				(width 0.1)
				(type default)
			)
			(layer "F.SilkS")
		)
		(fp_line
			(start -1.143 -0.5588)
			(end -1.143 0.5588)
			(stroke
				(width 0.1)
				(type default)
			)
			(layer "F.SilkS")
		)
		(fp_line
			(start 1.143 0.5588)
			(end 1.143 -0.5588)
			(stroke
				(width 0.1)
				(type default)
			)
			(layer "F.SilkS")
		)
		(fp_line
			(start -1.143 0.5588)
			(end 1.143 0.5588)
			(stroke
				(width 0.1)
				(type default)
			)
			(layer "F.SilkS")
		)
		(fp_poly
			(pts
				(xy -1.143 0.5588) (xy 1.143 0.5588) (xy 1.143 -0.5588) (xy -1.143 -0.5588)
			)
			(stroke
				(width 0)
				(type default)
			)
			(fill no)
			(layer "F.CrtYd")
		)
		(fp_line
			(start 0.508 -0.3048)
			(end -0.508 -0.3048)
			(stroke
				(width 0.1)
				(type default)
			)
			(layer "F.Fab")
		)
		(fp_line
			(start -0.508 -0.3048)
			(end -0.508 0.3048)
			(stroke
				(width 0.1)
				(type default)
			)
			(layer "F.Fab")
		)
		(fp_line
			(start 0.508 0.3048)
			(end 0.508 -0.3048)
			(stroke
				(width 0.1)
				(type default)
			)
			(layer "F.Fab")
		)
		(fp_line
			(start -0.508 0.3048)
			(end 0.508 0.3048)
			(stroke
				(width 0.1)
				(type default)
			)
			(layer "F.Fab")
		)
		(pad "1" smd rect
			(at -0.5334 0 90)
			(size 0.7112 0.6096)
			(layers "F.Cu" "F.Mask" "F.Paste")
			(net "FPGA_OUT_GPS_LED_BLUE_N")
		)
		(pad "2" smd rect
			(at 0.5334 0 90)
			(size 0.7112 0.6096)
			(layers "F.Cu" "F.Mask" "F.Paste")
			(net "UNNAMED_14_LED4PV14_I269_1")
		)
		(zone
			(layer "F.Cu")
			(hatch none 0.5)
			(connect_pads
				(clearance 0)
			)
			(min_thickness 0.25)
			(keepout
				(tracks not_allowed)
				(vias allowed)
				(pads allowed)
				(copperpour not_allowed)
				(footprints allowed)
			)
			(placement
				(enabled no)
				(sheetname "")
			)
			(fill
				(thermal_gap 0.5)
				(thermal_bridge_width 0.5)
				(island_removal_mode 0)
			)
			(polygon
				(pts
					(xy 6.1468 -81.4578) (xy 6.1468 -81.6102) (xy 5.5372 -81.6102) (xy 5.5372 -81.4578)
				)
			)
		)
		(zone
			(layer "F.Cu")
			(hatch none 0.5)
			(connect_pads
				(clearance 0)
			)
			(min_thickness 0.25)
			(keepout
				(tracks allowed)
				(vias not_allowed)
				(pads allowed)
				(copperpour not_allowed)
				(footprints allowed)
			)
			(placement
				(enabled no)
				(sheetname "")
			)
			(fill
				(thermal_gap 0.5)
				(thermal_bridge_width 0.5)
				(island_removal_mode 0)
			)
			(polygon
				(pts
					(xy 6.1468 -81.4578) (xy 6.1468 -81.6102) (xy 5.5372 -81.6102) (xy 5.5372 -81.4578)
				)
			)
		)
	)
	(footprint ""
		(layer "F.Cu")
		(at 42.164 -133.223)
		(property "Reference" "SP21"
			(at 0 0 0)
			(layer "F.SilkS")
			(hide yes)
			(effects
				(font
					(size 1.27 1.27)
				)
			)
		)
		(property "Value" ""
			(at 0 0 0)
			(layer "F.Fab")
			(effects
				(font
					(size 1.27 1.27)
				)
			)
		)
		(duplicate_pad_numbers_are_jumpers no)
	)
	(footprint ""
		(layer "F.Cu")
		(at 92.837 -70.993 90)
		(property "Reference" "TP55"
			(at 0.8636 -0.34925 90)
			(unlocked yes)
			(layer "F.SilkS")
			(effects
				(font
					(size 0.635 0.4064)
					(thickness 0.1524)
				)
				(justify left)
			)
		)
		(property "Value" ""
			(at 0 0 90)
			(layer "F.Fab")
			(effects
				(font
					(size 1.27 1.27)
				)
			)
		)
		(property "Device Type" "TP_PIONT-TP010CT020B030_PTH-TPA"
			(at -1.341882 0.996696 90)
			(unlocked yes)
			(layer "F.Fab")
			(hide yes)
			(effects
				(font
					(size 0.7874 0.5842)
					(thickness 0.1524)
				)
				(justify left)
			)
		)
		(duplicate_pad_numbers_are_jumpers no)
		(fp_poly
			(pts
				(arc
					(start 0 0.889)
					(mid 0 -0.889)
					(end 0 0.889)
				)
			)
			(stroke
				(width 0)
				(type default)
			)
			(fill no)
			(layer "B.CrtYd")
		)
		(fp_poly
			(pts
				(arc
					(start 0 0.889)
					(mid 0 -0.889)
					(end 0 0.889)
				)
			)
			(stroke
				(width 0)
				(type default)
			)
			(fill no)
			(layer "F.CrtYd")
		)
		(pad "1" thru_hole circle
			(at 0 0 90)
			(size 0.508 0.508)
			(drill 0.254)
			(layers "*.Cu" "*.Mask")
			(remove_unused_layers no)
			(net "XP1R2V_FPGA")
			(clearance 0.1016)
			(padstack
				(mode front_inner_back)
				(layer "Inner"
					(shape circle)
					(size 0.508 0.508)
					(clearance 0.1016)
				)
				(layer "B.Cu"
					(shape circle)
					(size 0.762 0.762)
					(clearance -0.0254)
				)
			)
		)
	)
)
